# T6G (Grand Teton) — schematic netlist excerpt (pin names and nets, part order shuffled) for the footprints in the layout excerpt that follows; sources: Cadence DE-HDL packaged netlist, KiCad conversion of 04192023_DAF0TMB3IC0_F0TG_MB_C_brd_V02_OCP.brd

J37  SCONN288_DDR506112002KQ  IO  pkg DDR288S_1-1VXC  page 109
  VIN_BULK0  = P12V_MEM_CPU1
  RFU0  = NC
  VIN_MGMT  = P3V3_AUX
  HSCL  = I3C_SPD_DDRL_CPU1_SCL
  HSDA  = I3C_SPD_DDRL_CPU1_SDA
  VSS0  = GND
  DQ0_A  = M_L_CPU1_SA_DQ<0>
  VSS1  = GND
  DQ1_A  = M_L_CPU1_SA_DQ<1>
  VSS2  = GND
  DQS0_A_T  = M_L_CPU1_SA_DQS_DP<0>
  DQS0_A_C  = M_L_CPU1_SA_DQS_DN<0>
  VSS3  = GND
  DQ4_A  = M_L_CPU1_SA_DQ<4>
  VSS4  = GND
  DQ5_A  = M_L_CPU1_SA_DQ<5>
  VSS5  = GND
  DQ8_A  = M_L_CPU1_SA_DQ<8>
  VSS6  = GND
  DQ9_A  = M_L_CPU1_SA_DQ<9>
  VSS7  = GND
  DQS1_A_T  = M_L_CPU1_SA_DQS_DP<1>
  DQS1_A_C  = M_L_CPU1_SA_DQS_DN<1>
  VSS8  = GND
  DQ12_A  = M_L_CPU1_SA_DQ<12>
  VSS9  = GND
  DQ13_A  = M_L_CPU1_SA_DQ<13>
  VSS10  = GND
  DQ16_A  = M_L_CPU1_SA_DQ<16>
  VSS11  = GND
  DQ17_A  = M_L_CPU1_SA_DQ<17>
  VSS12  = GND
  DQS2_A_T  = M_L_CPU1_SA_DQS_DP<2>
  DQS2_A_C  = M_L_CPU1_SA_DQS_DN<2>
  VSS13  = GND
  DQ20_A  = M_L_CPU1_SA_DQ<20>
  VSS14  = GND
  DQ21_A  = M_L_CPU1_SA_DQ<21>
  VSS15  = GND
  DQ24_A  = M_L_CPU1_SA_DQ<24>
  VSS16  = GND
  DQ25_A  = M_L_CPU1_SA_DQ<25>
  VSS17  = GND
  DQS3_A_T  = M_L_CPU1_SA_DQS_DP<3>
  DQS3_A_C  = M_L_CPU1_SA_DQS_DN<3>
  VSS18  = GND
  DQ28_A  = M_L_CPU1_SA_DQ<28>
  VSS19  = GND
  DQ29_A  = M_L_CPU1_SA_DQ<29>
  VSS20  = GND
  CB0_A  = M_L_CPU1_SA_CB<0>
  VSS21  = GND
  CB1_A  = M_L_CPU1_SA_CB<1>
  VSS22  = GND
  DQS4_A_T  = M_L_CPU1_SA_DQS_DP<4>
  DQS4_A_C  = M_L_CPU1_SA_DQS_DN<4>
  VSS23  = GND
  CB4_A  = M_L_CPU1_SA_CB<4>
  VSS24  = GND
  CB5_A  = M_L_CPU1_SA_CB<5>
  VSS25  = GND
  ALERT_N  = M_L_CPU1_ALERT_N
  VSS26  = GND
  CS0_A_N  = M_L_CPU1_SA_CS_N<0>
  VSS27  = GND
  CA0_A  = M_L_CPU1_SA_CA<0>
  VSS28  = GND
  CA2_A  = M_L_CPU1_SA_CA<2>
  VSS29  = GND
  CA4_A  = M_L_CPU1_SA_CA<4>
  VSS30  = GND
  CA6_A  = M_L_CPU1_SA_CA<6>
  VSS31  = GND
  PAR_A  = M_L_CPU1_SA_PAR
  VSS32  = GND
  CA0_B  = M_L_CPU1_SB_CA<0>
  VSS33  = GND
  CA2_B  = M_L_CPU1_SB_CA<2>
  VSS34  = GND
  CA4_B  = M_L_CPU1_SB_CA<4>
  VSS35  = GND
  CA6_B  = M_L_CPU1_SB_CA<6>
  VSS36  = GND
  CS0_B_N  = M_L_CPU1_SB_CS_N<0>
  VSS37  = GND
  \lbd||rsp_a_n\  = M_L_CPU1_SA_RSP<0>
  \lbs||rsp_b_n\  = M_L_CPU1_SB_RSP<0>
  VSS38  = GND
  CB4_B  = M_L_CPU1_SB_CB<4>
  VSS39  = GND
  CB5_B  = M_L_CPU1_SB_CB<5>
  VSS40  = GND
  \dqs9_b_t||tdqs9_b_t||dbi4_b_n\  = M_L_CPU1_SB_DQS_DP<9>
  \dqs9_b_c||tdqs9_b_c\  = M_L_CPU1_SB_DQS_DN<9>
  VSS41  = GND
  CB0_B  = M_L_CPU1_SB_CB<0>
  VSS42  = GND
  CB1_B  = M_L_CPU1_SB_CB<1>
  VSS43  = GND
  DQ0_B  = M_L_CPU1_SB_DQ<0>
  VSS44  = GND
  DQ1_B  = M_L_CPU1_SB_DQ<1>
  VSS45  = GND
  DQS0_B_T  = M_L_CPU1_SB_DQS_DP<0>
  DQS0_B_C  = M_L_CPU1_SB_DQS_DN<0>
  VSS46  = GND
  DQ4_B  = M_L_CPU1_SB_DQ<4>
  VSS47  = GND
  DQ5_B  = M_L_CPU1_SB_DQ<5>
  VSS48  = GND
  DQ8_B  = M_L_CPU1_SB_DQ<8>
  VSS49  = GND
  DQ9_B  = M_L_CPU1_SB_DQ<9>
  VSS50  = GND
  DQS1_B_T  = M_L_CPU1_SB_DQS_DP<1>
  DQS1_B_C  = M_L_CPU1_SB_DQS_DN<1>
  VSS51  = GND
  DQ12_B  = M_L_CPU1_SB_DQ<12>
  VSS52  = GND
  DQ13_B  = M_L_CPU1_SB_DQ<13>
  VSS53  = GND
  DQ16_B  = M_L_CPU1_SB_DQ<16>
  VSS54  = GND
  DQ17_B  = M_L_CPU1_SB_DQ<17>
  VSS55  = GND
  DQS2_B_T  = M_L_CPU1_SB_DQS_DP<2>
  DQS2_B_C  = M_L_CPU1_SB_DQS_DN<2>
  VSS56  = GND
  DQ20_B  = M_L_CPU1_SB_DQ<20>
  VSS57  = GND
  DQ21_B  = M_L_CPU1_SB_DQ<21>
  VSS58  = GND
  DQ24_B  = M_L_CPU1_SB_DQ<24>
  VSS59  = GND
  DQ25_B  = M_L_CPU1_SB_DQ<25>
  VSS60  = GND
  DQS3_B_T  = M_L_CPU1_SB_DQS_DP<3>
  DQS3_B_C  = M_L_CPU1_SB_DQS_DN<3>
  VSS61  = GND
  DQ28_B  = M_L_CPU1_SB_DQ<28>
  VSS62  = GND
  DQ29_B  = M_L_CPU1_SB_DQ<29>
  VSS63  = GND
  RFU1  = NC
  VIN_BULK1  = P12V_MEM_CPU1
  VIN_BULK2  = P12V_MEM_CPU1
  \pwr_good||fail_n\  = PWRGD_CHL_CPU1_DIMM
  HAS  = PD_CHL_CPU1_DIMM_SAA
  RFU2  = NC
  RFU3  = NC
  VSS64  = GND
  DQ2_A  = M_L_CPU1_SA_DQ<2>
  VSS65  = GND
  DQ3_A  = M_L_CPU1_SA_DQ<3>
  VSS66  = GND
  \dqs5_a_c||tdqs5_a_c||dqs5_a_t||tdqs5_a_t\  = M_L_CPU1_SA_DQS_DN<5>
  \dqs5_a_t||tdqs5_a_t\  = M_L_CPU1_SA_DQS_DP<5>
  VSS67  = GND
  DQ6_A  = M_L_CPU1_SA_DQ<6>
  VSS68  = GND
  DQ7_A  = M_L_CPU1_SA_DQ<7>
  VSS69  = GND
  DQ10_A  = M_L_CPU1_SA_DQ<10>
  VSS70  = GND
  DQ11_A  = M_L_CPU1_SA_DQ<11>
  VSS71  = GND
  \dqs6_a_c||tdqs6_a_c||dqs6_a_t||tdqs6_a_t\  = M_L_CPU1_SA_DQS_DN<6>
  \dqs6_a_t||tdqs6_a_t\  = M_L_CPU1_SA_DQS_DP<6>
  VSS72  = GND
  DQ14_A  = M_L_CPU1_SA_DQ<14>
  VSS73  = GND
  DQ15_A  = M_L_CPU1_SA_DQ<15>
  VSS74  = GND
  DQ18_A  = M_L_CPU1_SA_DQ<18>
  VSS75  = GND
  DQ19_A  = M_L_CPU1_SA_DQ<19>
  VSS76  = GND
  \dqs7_a_c||tdqs7_a_c\  = M_L_CPU1_SA_DQS_DN<7>
  \dqs7_a_t||tdqs7_a_t\  = M_L_CPU1_SA_DQS_DP<7>
  VSS77  = GND
  DQ22_A  = M_L_CPU1_SA_DQ<22>
  VSS78  = GND
  DQ23_A  = M_L_CPU1_SA_DQ<23>
  VSS79  = GND
  DQ26_A  = M_L_CPU1_SA_DQ<26>
  VSS80  = GND
  DQ27_A  = M_L_CPU1_SA_DQ<27>
  VSS81  = GND
  \dqs8_a_c||tdqs8_a_c\  = M_L_CPU1_SA_DQS_DN<8>
  \dqs8_a_t||tdqs8_a_t\  = M_L_CPU1_SA_DQS_DP<8>
  VSS82  = GND
  DQ30_A  = M_L_CPU1_SA_DQ<30>
  VSS83  = GND
  DQ31_A  = M_L_CPU1_SA_DQ<31>
  VSS84  = GND
  CB2_A  = M_L_CPU1_SA_CB<2>
  VSS85  = GND
  CB3_A  = M_L_CPU1_SA_CB<3>
  VSS86  = GND
  \dqs9_a_c||tdqs9_a_c\  = M_L_CPU1_SA_DQS_DN<9>
  \dqs9_a_t||tdqs9_a_t\  = M_L_CPU1_SA_DQS_DP<9>
  VSS87  = GND
  CB6_A  = M_L_CPU1_SA_CB<6>
  VSS88  = GND
  CB7_A  = M_L_CPU1_SA_CB<7>
  VSS89  = GND
  RESET_N  = M_L_CPU1_RESET_N
  VSS90  = GND
  CS1_A_N  = M_L_CPU1_SA_CS_N<1>
  VSS91  = GND
  CA1_A  = M_L_CPU1_SA_CA<1>
  VSS92  = GND
  CA3_A  = M_L_CPU1_SA_CA<3>
  VSS93  = GND
  CA5_A  = M_L_CPU1_SA_CA<5>
  VSS94  = GND
  CK_T  = M_L_CPU1_CLK_DP<0>
  CK_C  = M_L_CPU1_CLK_DN<0>
  VSS95  = GND
  RFU4  = NC
  CA1_B  = M_L_CPU1_SB_CA<1>
  VSS96  = GND
  CA3_B  = M_L_CPU1_SB_CA<3>
  VSS97  = GND
  CA5_B  = M_L_CPU1_SB_CA<5>
  VSS98  = GND
  PAR_B  = M_L_CPU1_SB_PAR
  VSS99  = GND
  CS1_B_N  = M_L_CPU1_SB_CS_N<1>
  VSS100  = GND
  RFU5  = NC
  RFU6  = NC
  VSS101  = GND
  CB6_B  = M_L_CPU1_SB_CB<6>
  VSS102  = GND
  CB7_B  = M_L_CPU1_SB_CB<7>
  VSS103  = GND
  DQS4_B_C  = M_L_CPU1_SB_DQS_DN<4>
  DQS4_B_T  = M_L_CPU1_SB_DQS_DP<4>
  VSS104  = GND
  CB2_B  = M_L_CPU1_SB_CB<2>
  VSS105  = GND
  CB3_B  = M_L_CPU1_SB_CB<3>
  VSS106  = GND
  DQ2_B  = M_L_CPU1_SB_DQ<2>
  VSS107  = GND
  DQ3_B  = M_L_CPU1_SB_DQ<3>
  VSS108  = GND
  \dqs5_b_c||tdqs5_b_c\  = M_L_CPU1_SB_DQS_DN<5>
  \dqs5_b_t||tdqs5_b_t\  = M_L_CPU1_SB_DQS_DP<5>
  VSS109  = GND
  DQ6_B  = M_L_CPU1_SB_DQ<6>
  VSS110  = GND
  DQ7_B  = M_L_CPU1_SB_DQ<7>
  VSS111  = GND
  DQ10_B  = M_L_CPU1_SB_DQ<10>
  VSS112  = GND
  DQ11_B  = M_L_CPU1_SB_DQ<11>
  VSS113  = GND
  \dqs6_b_c||tdqs6_b_c\  = M_L_CPU1_SB_DQS_DN<6>
  \dqs6_b_t||tdqs6_b_t\  = M_L_CPU1_SB_DQS_DP<6>
  VSS114  = GND
  DQ14_B  = M_L_CPU1_SB_DQ<14>
  VSS115  = GND
  DQ15_B  = M_L_CPU1_SB_DQ<15>
  VSS116  = GND
  DQ18_B  = M_L_CPU1_SB_DQ<18>
  VSS117  = GND
  DQ19_B  = M_L_CPU1_SB_DQ<19>
  VSS118  = GND
  \dqs7_b_c||tdqs7_b_c\  = M_L_CPU1_SB_DQS_DN<7>
  \dqs7_b_t||tdqs7_b_t\  = M_L_CPU1_SB_DQS_DP<7>
  VSS119  = GND
  DQ22_B  = M_L_CPU1_SB_DQ<22>
  VSS120  = GND
  DQ23_B  = M_L_CPU1_SB_DQ<23>
  VSS121  = GND
  DQ26_B  = M_L_CPU1_SB_DQ<26>
  VSS122  = GND
  DQ27_B  = M_L_CPU1_SB_DQ<27>
  VSS123  = GND
  \dqs8_b_c||tdqs8_b_c\  = M_L_CPU1_SB_DQS_DN<8>
  \dqs8_b_t||tdqs8_b_t\  = M_L_CPU1_SB_DQS_DP<8>
  VSS124  = GND
  DQ30_B  = M_L_CPU1_SB_DQ<30>
  VSS125  = GND
  DQ31_B  = M_L_CPU1_SB_DQ<31>
  VSS126  = GND
  G1  = GND
  G2  = GND
  G3  = GND

(kicad_pcb
	(version 20260206)
	(generator "pcbnew")
	(generator_version "10.0")
	(general
		(thickness 1.6)
		(legacy_teardrops no)
	)
	(paper "A4")
	(title_block
		(title "04192023_DAF0TMB3IC0_F0TG_MB_C_brd_V02_OCP.brd")
		(comment 1 "Grand Teton / footprint 34 of 8354 (J37), pads 277-291 of 291")
	)
	(layers
		(0 "F.Cu" signal "TOP")
		(4 "In1.Cu" signal "GND")
		(6 "In2.Cu" signal "IN1")
		(8 "In3.Cu" signal "GND1")
		(10 "In4.Cu" signal "IN2")
		(12 "In5.Cu" signal "GND2")
		(14 "In6.Cu" signal "IN3")
		(16 "In7.Cu" signal "GND3")
		(18 "In8.Cu" signal "VCC")
		(20 "In9.Cu" signal "VCC1")
		(22 "In10.Cu" signal "GND4")
		(24 "In11.Cu" signal "IN4")
		(26 "In12.Cu" signal "GND5")
		(28 "In13.Cu" signal "IN5")
		(30 "In14.Cu" signal "GND6")
		(32 "In15.Cu" signal "IN6")
		(34 "In16.Cu" signal "GND7")
		(2 "B.Cu" signal "BOTTOM")
		(9 "F.Adhes" user "F.Adhesive")
		(11 "B.Adhes" user "B.Adhesive")
		(13 "F.Paste" user "Package Geometry/Pastemask Top")
		(15 "B.Paste" user "Package Geometry/Pastemask Bottom")
		(5 "F.SilkS" user "Ref Des/Silkscreen Top")
		(7 "B.SilkS" user "Ref Des/Silkscreen Bottom")
		(1 "F.Mask" user "Board Geometry/Soldermask Top")
		(3 "B.Mask" user "Board Geometry/Soldermask Bottom")
		(17 "Dwgs.User" user "User.Drawings")
		(19 "Cmts.User" user "User.Comments")
		(21 "Eco1.User" user "User.Eco1")
		(23 "Eco2.User" user "User.Eco2")
		(25 "Edge.Cuts" user "Board Geometry/Outline")
		(27 "Margin" user)
		(31 "F.CrtYd" user "Package Geometry/Place Bound Top")
		(29 "B.CrtYd" user "Package Geometry/Place Bound Bottom")
		(35 "F.Fab" user "Ref Des/Assembly Top")
		(33 "B.Fab" user "Ref Des/Assembly Bottom")
	)
	(footprint ""
		(layer "F.Cu")
		(at 204.197966 -255.560322 180)
		(property "Reference" "J37"
			(at 2.8702 -81.730088 0)
			(unlocked yes)
			(layer "F.SilkS")
			(effects
				(font
					(size 0.7874 0.5842)
					(thickness 0.1524)
				)
			)
		)
		(property "Value" ""
			(at 0 0 180)
			(layer "F.Fab")
			(effects
				(font
					(size 1.27 1.27)
				)
			)
		)
		(duplicate_pad_numbers_are_jumpers no)
		(pad "277" smd rect
			(at 2.050034 53.975 90)
			(size 0.519938 1.4986)
			(layers "F.Cu" "F.Mask" "F.Paste")
			(net "GND")
		)
		(pad "278" smd rect
			(at 2.050034 54.824884 90)
			(size 0.519938 1.4986)
			(layers "F.Cu" "F.Mask" "F.Paste")
			(net "M_L_CPU1_SB_DQ<26>")
		)
		(pad "279" smd rect
			(at 2.050034 55.675022 90)
			(size 0.519938 1.4986)
			(layers "F.Cu" "F.Mask" "F.Paste")
			(net "GND")
		)
		(pad "280" smd rect
			(at 2.050034 56.524906 90)
			(size 0.519938 1.4986)
			(layers "F.Cu" "F.Mask" "F.Paste")
			(net "M_L_CPU1_SB_DQ<27>")
		)
		(pad "281" smd rect
			(at 2.050034 57.375044 90)
			(size 0.519938 1.4986)
			(layers "F.Cu" "F.Mask" "F.Paste")
			(net "GND")
		)
		(pad "282" smd rect
			(at 2.050034 58.224928 90)
			(size 0.519938 1.4986)
			(layers "F.Cu" "F.Mask" "F.Paste")
			(net "M_L_CPU1_SB_DQS_DN<8>")
		)
		(pad "283" smd rect
			(at 2.050034 59.075066 90)
			(size 0.519938 1.4986)
			(layers "F.Cu" "F.Mask" "F.Paste")
			(net "M_L_CPU1_SB_DQS_DP<8>")
		)
		(pad "284" smd rect
			(at 2.050034 59.92495 90)
			(size 0.519938 1.4986)
			(layers "F.Cu" "F.Mask" "F.Paste")
			(net "GND")
		)
		(pad "285" smd rect
			(at 2.050034 60.775088 90)
			(size 0.519938 1.4986)
			(layers "F.Cu" "F.Mask" "F.Paste")
			(net "M_L_CPU1_SB_DQ<30>")
		)
		(pad "286" smd rect
			(at 2.050034 61.624972 90)
			(size 0.519938 1.4986)
			(layers "F.Cu" "F.Mask" "F.Paste")
			(net "GND")
		)
		(pad "287" smd rect
			(at 2.050034 62.47511 90)
			(size 0.519938 1.4986)
			(layers "F.Cu" "F.Mask" "F.Paste")
			(net "M_L_CPU1_SB_DQ<31>")
		)
		(pad "288" smd rect
			(at 2.050034 63.324994 90)
			(size 0.519938 1.4986)
			(layers "F.Cu" "F.Mask" "F.Paste")
			(net "GND")
		)
		(pad "G1" thru_hole oval
			(at 0 -68.97497 90)
			(size 1.7272 3.4798)
			(drill oval 1.2192 2.4638)
			(layers "*.Cu" "*.Mask")
			(remove_unused_layers no)
			(net "GND")
			(clearance 0.127)
			(thermal_gap 0.127)
		)
		(pad "G2" thru_hole oval
			(at 0 3.875024 90)
			(size 1.7272 3.4798)
			(drill oval 1.2192 2.4638)
			(layers "*.Cu" "*.Mask")
			(remove_unused_layers no)
			(net "GND")
			(clearance 0.127)
			(thermal_gap 0.127)
		)
		(pad "G3" thru_hole oval
			(at 0 68.97497 90)
			(size 1.7272 3.4798)
			(drill oval 1.2192 2.4638)
			(layers "*.Cu" "*.Mask")
			(remove_unused_layers no)
			(net "GND")
			(clearance 0.127)
			(thermal_gap 0.127)
		)
	)
)
